# S9S_MB_2U (Grand Teton) — schematic netlist excerpt (pin names and nets, part order shuffled) for the footprints in the layout excerpt that follows; sources: Cadence DE-HDL packaged netlist, KiCad conversion of 03242023_DA0F0TMBIJ0_F0T_Motherboard_J_brd_V01_OCP.brd

C1206  Q_CAP  10UF 6.3V 20% X6S  pkg C0402  page 189 : A = P3V3_AUX ; B = GND
R302  Q_RES  0 5% CHIP  pkg 0402LF  page 118 : A = H_CPU0_RMCA_LVC1_R_N ; B = H_CPU_RMCA_LVC1_R_N

(kicad_pcb
	(version 20260206)
	(generator "pcbnew")
	(generator_version "10.0")
	(general
		(thickness 1.6)
		(legacy_teardrops no)
	)
	(paper "A4")
	(title_block
		(title "03242023_DA0F0TMBIJ0_F0T_Motherboard_J_brd_V01_OCP.brd")
		(comment 1 "Grand Teton / footprints 5211-5212 of 6105")
	)
	(layers
		(0 "F.Cu" signal "TOP")
		(4 "In1.Cu" signal "GND")
		(6 "In2.Cu" signal "IN1")
		(8 "In3.Cu" signal "GND1")
		(10 "In4.Cu" signal "IN2")
		(12 "In5.Cu" signal "GND2")
		(14 "In6.Cu" signal "IN3")
		(16 "In7.Cu" signal "GND3")
		(18 "In8.Cu" signal "VCC")
		(20 "In9.Cu" signal "VCC1")
		(22 "In10.Cu" signal "GND4")
		(24 "In11.Cu" signal "IN4")
		(26 "In12.Cu" signal "GND5")
		(28 "In13.Cu" signal "IN5")
		(30 "In14.Cu" signal "GND6")
		(32 "In15.Cu" signal "IN6")
		(34 "In16.Cu" signal "GND7")
		(2 "B.Cu" signal "BOTTOM")
		(9 "F.Adhes" user "F.Adhesive")
		(11 "B.Adhes" user "B.Adhesive")
		(13 "F.Paste" user "Package Geometry/Pastemask Top")
		(15 "B.Paste" user "Package Geometry/Pastemask Bottom")
		(5 "F.SilkS" user "Ref Des/Silkscreen Top")
		(7 "B.SilkS" user "Ref Des/Silkscreen Bottom")
		(1 "F.Mask" user "Board Geometry/Soldermask Top")
		(3 "B.Mask" user "Board Geometry/Soldermask Bottom")
		(17 "Dwgs.User" user "User.Drawings")
		(19 "Cmts.User" user "User.Comments")
		(21 "Eco1.User" user "User.Eco1")
		(23 "Eco2.User" user "User.Eco2")
		(25 "Edge.Cuts" user "Board Geometry/Outline")
		(27 "Margin" user)
		(31 "F.CrtYd" user "Package Geometry/Place Bound Top")
		(29 "B.CrtYd" user "Package Geometry/Place Bound Bottom")
		(35 "F.Fab" user "Ref Des/Assembly Top")
		(33 "B.Fab" user "Ref Des/Assembly Bottom")
	)
	(footprint ""
		(layer "B.Cu")
		(at 323.661278 -188.48451 90)
		(property "Reference" "R302"
			(at 0 0 90)
			(layer "B.SilkS")
			(hide yes)
			(effects
				(font
					(size 1.27 1.27)
				)
				(justify mirror)
			)
		)
		(property "Value" ""
			(at 0 0 90)
			(layer "B.Fab")
			(effects
				(font
					(size 1.27 1.27)
				)
				(justify mirror)
			)
		)
		(duplicate_pad_numbers_are_jumpers no)
		(fp_line
			(start 0.7874 -0.4064)
			(end -0.7874 -0.4064)
			(stroke
				(width 0.1524)
				(type default)
			)
			(layer "B.SilkS")
		)
		(fp_line
			(start -0.7874 -0.4064)
			(end -0.7874 0.4064)
			(stroke
				(width 0.1524)
				(type default)
			)
			(layer "B.SilkS")
		)
		(fp_line
			(start 0.7874 0.4064)
			(end 0.7874 -0.4064)
			(stroke
				(width 0.1524)
				(type default)
			)
			(layer "B.SilkS")
		)
		(fp_line
			(start -0.7874 0.4064)
			(end 0.7874 0.4064)
			(stroke
				(width 0.1524)
				(type default)
			)
			(layer "B.SilkS")
		)
		(fp_line
			(start 0.67945 -0.305054)
			(end 0.12065 -0.305054)
			(stroke
				(width 0.1)
				(type default)
			)
			(layer "B.Fab")
		)
		(fp_line
			(start 0.12065 -0.305054)
			(end 0.12065 -0.2794)
			(stroke
				(width 0.1)
				(type default)
			)
			(layer "B.Fab")
		)
		(fp_line
			(start -0.12065 -0.3048)
			(end -0.67945 -0.3048)
			(stroke
				(width 0.1)
				(type default)
			)
			(layer "B.Fab")
		)
		(fp_line
			(start -0.67945 -0.3048)
			(end -0.67945 0.3048)
			(stroke
				(width 0.1)
				(type default)
			)
			(layer "B.Fab")
		)
		(fp_line
			(start 0.12065 -0.2794)
			(end -0.12065 -0.2794)
			(stroke
				(width 0.1)
				(type default)
			)
			(layer "B.Fab")
		)
		(fp_line
			(start -0.12065 -0.2794)
			(end -0.12065 -0.3048)
			(stroke
				(width 0.1)
				(type default)
			)
			(layer "B.Fab")
		)
		(fp_line
			(start 0.12065 0.2794)
			(end 0.12065 0.3048)
			(stroke
				(width 0.1)
				(type default)
			)
			(layer "B.Fab")
		)
		(fp_line
			(start -0.120396 0.2794)
			(end 0.12065 0.2794)
			(stroke
				(width 0.1)
				(type default)
			)
			(layer "B.Fab")
		)
		(fp_line
			(start 0.67945 0.3048)
			(end 0.67945 -0.305054)
			(stroke
				(width 0.1)
				(type default)
			)
			(layer "B.Fab")
		)
		(fp_line
			(start 0.12065 0.3048)
			(end 0.67945 0.3048)
			(stroke
				(width 0.1)
				(type default)
			)
			(layer "B.Fab")
		)
		(fp_line
			(start -0.120396 0.3048)
			(end -0.120396 0.2794)
			(stroke
				(width 0.1)
				(type default)
			)
			(layer "B.Fab")
		)
		(fp_line
			(start -0.67945 0.3048)
			(end -0.120396 0.3048)
			(stroke
				(width 0.1)
				(type default)
			)
			(layer "B.Fab")
		)
		(pad "1" smd circle
			(at 0.40005 0 270)
			(size 0 0)
			(layers "B.Cu" "B.Mask" "B.Paste")
			(net "H_CPU0_RMCA_LVC1_R_N")
		)
		(pad "2" smd circle
			(at -0.40005 0 270)
			(size 0 0)
			(layers "B.Cu" "B.Mask" "B.Paste")
			(net "H_CPU_RMCA_LVC1_R_N")
		)
	)
	(footprint ""
		(layer "B.Cu")
		(at 333.786988 -44.962064)
		(property "Reference" "C1206"
			(at 0 0 0)
			(layer "B.SilkS")
			(hide yes)
			(effects
				(font
					(size 1.27 1.27)
				)
				(justify mirror)
			)
		)
		(property "Value" ""
			(at 0 0 0)
			(layer "B.Fab")
			(effects
				(font
					(size 1.27 1.27)
				)
				(justify mirror)
			)
		)
		(duplicate_pad_numbers_are_jumpers no)
		(fp_line
			(start -0.7874 -0.4064)
			(end -0.7874 0.4064)
			(stroke
				(width 0.1524)
				(type default)
			)
			(layer "B.SilkS")
		)
		(fp_line
			(start -0.7874 0.4064)
			(end 0.7874 0.4064)
			(stroke
				(width 0.1524)
				(type default)
			)
			(layer "B.SilkS")
		)
		(fp_line
			(start 0.7874 -0.4064)
			(end -0.7874 -0.4064)
			(stroke
				(width 0.1524)
				(type default)
			)
			(layer "B.SilkS")
		)
		(fp_line
			(start 0.7874 0.4064)
			(end 0.7874 -0.4064)
			(stroke
				(width 0.1524)
				(type default)
			)
			(layer "B.SilkS")
		)
		(fp_line
			(start -0.67945 -0.3048)
			(end -0.67945 0.3048)
			(stroke
				(width 0.1)
				(type default)
			)
			(layer "B.Fab")
		)
		(fp_line
			(start -0.67945 0.3048)
			(end -0.120396 0.3048)
			(stroke
				(width 0.1)
				(type default)
			)
			(layer "B.Fab")
		)
		(fp_line
			(start -0.12065 -0.3048)
			(end -0.67945 -0.3048)
			(stroke
				(width 0.1)
				(type default)
			)
			(layer "B.Fab")
		)
		(fp_line
			(start -0.12065 -0.2794)
			(end -0.12065 -0.3048)
			(stroke
				(width 0.1)
				(type default)
			)
			(layer "B.Fab")
		)
		(fp_line
			(start -0.120396 0.2794)
			(end 0.12065 0.2794)
			(stroke
				(width 0.1)
				(type default)
			)
			(layer "B.Fab")
		)
		(fp_line
			(start -0.120396 0.3048)
			(end -0.120396 0.2794)
			(stroke
				(width 0.1)
				(type default)
			)
			(layer "B.Fab")
		)
		(fp_line
			(start 0.12065 -0.305054)
			(end 0.12065 -0.2794)
			(stroke
				(width 0.1)
				(type default)
			)
			(layer "B.Fab")
		)
		(fp_line
			(start 0.12065 -0.2794)
			(end -0.12065 -0.2794)
			(stroke
				(width 0.1)
				(type default)
			)
			(layer "B.Fab")
		)
		(fp_line
			(start 0.12065 0.2794)
			(end 0.12065 0.3048)
			(stroke
				(width 0.1)
				(type default)
			)
			(layer "B.Fab")
		)
		(fp_line
			(start 0.12065 0.3048)
			(end 0.67945 0.3048)
			(stroke
				(width 0.1)
				(type default)
			)
			(layer "B.Fab")
		)
		(fp_line
			(start 0.67945 -0.305054)
			(end 0.12065 -0.305054)
			(stroke
				(width 0.1)
				(type default)
			)
			(layer "B.Fab")
		)
		(fp_line
			(start 0.67945 0.3048)
			(end 0.67945 -0.305054)
			(stroke
				(width 0.1)
				(type default)
			)
			(layer "B.Fab")
		)
		(pad "1" smd circle
			(at 0.40005 0 180)
			(size 0 0)
			(layers "B.Cu" "B.Mask" "B.Paste")
			(net "P3V3_AUX")
		)
		(pad "2" smd circle
			(at -0.40005 0 180)
			(size 0 0)
			(layers "B.Cu" "B.Mask" "B.Paste")
			(net "GND")
		)
	)
)
